G04 ================== begin FILE IDENTIFICATION RECORD ==================*
G04 Layout Name:  D:/<user>/Wistron_project/16347-sc/gbr/16347-sc.brd*
G04 Film Name:    TMASK*
G04 File Format:  Gerber RS274X*
G04 File Origin:  Cadence Allegro 16.5-S056*
G04 Origin Date:  Tue Mar 14 17:08:18 2017*
G04 *
G04 Layer:  VIA CLASS/SOLDERMASK_TOP*
G04 Layer:  PIN/SOLDERMASK_TOP*
G04 Layer:  PACKAGE GEOMETRY/SOLDERMASK_TOP*
G04 Layer:  DRAWING FORMAT/LAYER_PCB_STORY*
G04 Layer:  DRAWING FORMAT/LAYER_SOLDER_T*
G04 Layer:  BOARD GEOMETRY/SOLDERMASK_TOP*
G04 *
G04 Offset:    (0.00 0.00)*
G04 Mirror:    No*
G04 Mode:      Positive*
G04 Rotation:  0*
G04 FullContactRelief:  No*
G04 UndefLineWidth:     6.00*
G04 ================== end FILE IDENTIFICATION RECORD ====================*
%FSLAX35Y35*MOIN*%
%IR0*IPPOS*OFA0.00000B0.00000*MIA0B0*SFA1.00000B1.00000*%
%ADD15C,.026*%
%ADD13C,.08*%
%ADD10C,.086*%
%ADD12C,.115*%
%ADD14R,.028X.034*%
%ADD11C,.237*%
%ADD16C,.02*%
%ADD17C,.006*%
G75*
%LPD*%
G75*
G54D10*
X35185Y15572D03*
X16240Y99213D03*
Y233859D03*
Y368505D03*
Y503151D03*
Y637797D03*
Y772443D03*
Y907089D03*
X693024Y26550D03*
X784745Y19685D03*
Y154331D03*
Y288977D03*
Y423623D03*
Y558269D03*
Y692915D03*
Y827561D03*
G54D11*
X16240Y19684D03*
X301968Y19685D03*
X488681Y19684D03*
X712106D03*
G54D12*
X47737Y19685D03*
X680610D03*
G54D13*
X35851Y28624D03*
X48411Y920770D03*
X693601Y10159D03*
X751130Y826309D03*
X765026Y19107D03*
G54D14*
X55513Y61930D03*
X51573D03*
X55513Y56180D03*
X51573D03*
X179726Y61930D03*
X175786D03*
X179726Y56180D03*
X175786D03*
X303939Y61930D03*
X299999D03*
X303939Y56180D03*
X299999D03*
X424211Y61930D03*
Y56180D03*
X428151Y61930D03*
Y56180D03*
X552364Y61930D03*
X548424D03*
X552364Y56180D03*
X548424D03*
X676576Y61930D03*
X672636D03*
X676576Y56180D03*
X672636D03*
G54D15*
X53632Y45628D03*
X97400Y24300D03*
X176835Y43904D03*
X179708Y49915D03*
X173169Y49700D03*
X171596Y44154D03*
X207900Y43000D03*
X296600Y47000D03*
X387700Y23700D03*
X422646Y46356D03*
X548049Y46414D03*
X671209Y45487D03*
G54D16*
G01X-23515Y-108314D02*
X-55515D01*
G01X-23515Y-124314D02*
Y-204314D01*
G01D02*
X1177585D01*
G01X-27515Y-108314D02*
G02I-12000J0D01*
G01X-39515Y-124314D02*
Y-92314D01*
G01X-23515Y-124314D02*
X1177585D01*
G01X-23515Y-159814D02*
X1177585D01*
G01X-32665Y-108314D02*
G02I-6850J0D01*
G01X390085Y-124314D02*
Y-204314D01*
G01X527585Y-124314D02*
Y-204314D01*
G01X642585Y-124314D02*
Y-204314D01*
G01X810085Y-124314D02*
Y-204314D01*
G01X980085Y-124314D02*
Y-204314D01*
G01X1177585Y-124314D02*
Y-204314D01*
G01X1205585Y-108314D02*
G02I-12000J0D01*
G01X1200435D02*
G02I-6850J0D01*
G01X1209585D02*
X1177585D01*
G01X1193585Y-124314D02*
Y-92314D01*
G54D17*
G01X981Y-184981D02*
X1855Y-184106D01*
X2510Y-182648D01*
X2947Y-180605D01*
X2510Y-178856D01*
X1637Y-177689D01*
X108Y-176814D01*
X-5787D01*
Y-194314D01*
X1418D01*
X2947Y-193148D01*
X3820Y-191397D01*
X4257Y-189356D01*
X3820Y-187314D01*
X2510Y-185564D01*
X981Y-184981D01*
X-5787D01*
G01X13678Y-194314D02*
Y-182648D01*
G01Y-184981D02*
X14770Y-183814D01*
X15862Y-182939D01*
X17390Y-182648D01*
X18481Y-182939D01*
X19792Y-183814D01*
G01X29650Y-199564D02*
X30960Y-200147D01*
X32707Y-199564D01*
X33798Y-198398D01*
X34672Y-196939D01*
X35981Y-192273D01*
X38820Y-182648D01*
G01X31833D02*
X35981Y-192273D01*
G01X55228Y-184106D02*
X53700Y-182939D01*
X52390Y-182648D01*
X50643Y-183231D01*
X49333Y-184397D01*
X48460Y-186439D01*
X48241Y-188481D01*
X48460Y-190523D01*
X49333Y-192273D01*
X50643Y-193731D01*
X52390Y-194314D01*
X53918Y-193731D01*
X55228Y-192564D01*
G01X65960Y-186439D02*
X72947D01*
X72292Y-184397D01*
X71200Y-183231D01*
X69672Y-182648D01*
X68143Y-182939D01*
X66833Y-183814D01*
X65960Y-185856D01*
X65523Y-187606D01*
Y-189356D01*
X65960Y-191106D01*
X67052Y-192856D01*
X68362Y-194022D01*
X69890Y-194314D01*
X71418Y-193731D01*
X72947Y-191981D01*
G01X109038Y-178273D02*
X107728Y-177397D01*
X106200Y-176814D01*
X104453D01*
X102488Y-177689D01*
X100960Y-179147D01*
X99868Y-180898D01*
X98995Y-183814D01*
X98776Y-186439D01*
X99213Y-189064D01*
X99868Y-190814D01*
X101178Y-192564D01*
X102707Y-193731D01*
X104235Y-194314D01*
X105763D01*
X107292Y-193731D01*
X108602Y-192856D01*
X109694Y-191690D01*
G01X125665Y-194314D02*
Y-182648D01*
G01Y-184689D02*
X124792Y-183523D01*
X123481Y-182939D01*
X121953Y-182648D01*
X120425Y-183231D01*
X119115Y-184397D01*
X118241Y-186147D01*
X117805Y-188481D01*
X118241Y-190814D01*
X119115Y-192564D01*
X120425Y-193731D01*
X121953Y-194314D01*
X123481Y-194022D01*
X124792Y-193148D01*
X125665Y-191981D01*
G01X135523Y-194314D02*
Y-182648D01*
G01Y-185564D02*
X136397Y-184106D01*
X137707Y-182939D01*
X139453Y-182648D01*
X140981Y-182939D01*
X142292Y-184106D01*
X142947Y-186147D01*
Y-194314D01*
G01X152150Y-199564D02*
X153460Y-200147D01*
X155207Y-199564D01*
X156298Y-198398D01*
X157172Y-196939D01*
X158481Y-192273D01*
X161320Y-182648D01*
G01X154333D02*
X158481Y-192273D01*
G01X174235Y-194314D02*
X172925Y-194022D01*
X171615Y-192856D01*
X170741Y-190814D01*
X170305Y-188481D01*
X170741Y-186147D01*
X171615Y-184106D01*
X172925Y-182939D01*
X174235Y-182648D01*
X175545Y-182939D01*
X176855Y-184106D01*
X177728Y-186147D01*
X177947Y-188481D01*
X177728Y-190814D01*
X176855Y-192856D01*
X175545Y-194022D01*
X174235Y-194314D01*
G01X188023D02*
Y-182648D01*
G01Y-185564D02*
X188897Y-184106D01*
X190207Y-182939D01*
X191953Y-182648D01*
X193481Y-182939D01*
X194792Y-184106D01*
X195447Y-186147D01*
Y-194314D01*
G01X222368Y-176814D02*
Y-194314D01*
X231102D01*
G01X248602D02*
X239868D01*
Y-176814D01*
X248602D01*
G01X245108Y-185272D02*
X239868D01*
G01X256932Y-194314D02*
Y-176814D01*
X261298D01*
X263045Y-177689D01*
X264355Y-178856D01*
X265447Y-180605D01*
X266320Y-182648D01*
X266538Y-185564D01*
X266320Y-188481D01*
X265447Y-190523D01*
X264355Y-192273D01*
X263045Y-193439D01*
X261298Y-194314D01*
X256932D01*
G01X298481Y-184981D02*
X299355Y-184106D01*
X300010Y-182648D01*
X300447Y-180605D01*
X300010Y-178856D01*
X299137Y-177689D01*
X297608Y-176814D01*
X291713D01*
Y-194314D01*
X298918D01*
X300447Y-193148D01*
X301320Y-191397D01*
X301757Y-189356D01*
X301320Y-187314D01*
X300010Y-185564D01*
X298481Y-184981D01*
X291713D01*
G01X314235Y-194314D02*
X312925Y-194022D01*
X311615Y-192856D01*
X310741Y-190814D01*
X310305Y-188481D01*
X310741Y-186147D01*
X311615Y-184106D01*
X312925Y-182939D01*
X314235Y-182648D01*
X315545Y-182939D01*
X316855Y-184106D01*
X317728Y-186147D01*
X317947Y-188481D01*
X317728Y-190814D01*
X316855Y-192856D01*
X315545Y-194022D01*
X314235Y-194314D01*
G01X335665D02*
Y-182648D01*
G01Y-184689D02*
X334792Y-183523D01*
X333481Y-182939D01*
X331953Y-182648D01*
X330425Y-183231D01*
X329115Y-184397D01*
X328241Y-186147D01*
X327805Y-188481D01*
X328241Y-190814D01*
X329115Y-192564D01*
X330425Y-193731D01*
X331953Y-194314D01*
X333481Y-194022D01*
X334792Y-193148D01*
X335665Y-191981D01*
G01X346178Y-194314D02*
Y-182648D01*
G01Y-184981D02*
X347270Y-183814D01*
X348362Y-182939D01*
X349890Y-182648D01*
X350981Y-182939D01*
X352292Y-183814D01*
G01X370665Y-176814D02*
Y-194314D01*
G01Y-191690D02*
X369792Y-193148D01*
X368481Y-194022D01*
X366953Y-194314D01*
X365207Y-193731D01*
X363897Y-192273D01*
X363023Y-190523D01*
X362805Y-188481D01*
X363023Y-186439D01*
X363897Y-184689D01*
X365207Y-183231D01*
X366953Y-182648D01*
X368481Y-182939D01*
X369573Y-183523D01*
X370665Y-184689D01*
G01X142308Y-149314D02*
Y-131814D01*
X147985Y-146397D01*
X153662Y-131814D01*
Y-149314D01*
G01X165485D02*
X164175Y-149022D01*
X162865Y-147856D01*
X161991Y-145814D01*
X161555Y-143481D01*
X161991Y-141147D01*
X162865Y-139106D01*
X164175Y-137939D01*
X165485Y-137648D01*
X166795Y-137939D01*
X168105Y-139106D01*
X168978Y-141147D01*
X169197Y-143481D01*
X168978Y-145814D01*
X168105Y-147856D01*
X166795Y-149022D01*
X165485Y-149314D01*
G01X186915Y-131814D02*
Y-149314D01*
G01Y-146690D02*
X186042Y-148148D01*
X184731Y-149022D01*
X183203Y-149314D01*
X181457Y-148731D01*
X180147Y-147273D01*
X179273Y-145523D01*
X179055Y-143481D01*
X179273Y-141439D01*
X180147Y-139689D01*
X181457Y-138231D01*
X183203Y-137648D01*
X184731Y-137939D01*
X185823Y-138523D01*
X186915Y-139689D01*
G01X197210Y-141439D02*
X204197D01*
X203542Y-139397D01*
X202450Y-138231D01*
X200922Y-137648D01*
X199393Y-137939D01*
X198083Y-138814D01*
X197210Y-140856D01*
X196773Y-142606D01*
Y-144356D01*
X197210Y-146106D01*
X198302Y-147856D01*
X199612Y-149022D01*
X201140Y-149314D01*
X202668Y-148731D01*
X204197Y-146981D01*
G01X217985Y-149314D02*
Y-131814D01*
G01X423785Y-194314D02*
Y-176814D01*
X421165Y-180314D01*
G01Y-194314D02*
X426405D01*
G01X437137Y-187023D02*
X438665Y-184981D01*
X439975Y-183814D01*
X441722Y-183231D01*
X443250Y-183814D01*
X444342Y-184981D01*
X445215Y-186731D01*
X445433Y-188772D01*
X445215Y-190523D01*
X444342Y-192273D01*
X443031Y-193731D01*
X441503Y-194314D01*
X439757Y-193731D01*
X438228Y-191981D01*
X437355Y-189356D01*
X437137Y-186439D01*
X437573Y-182648D01*
X438228Y-180605D01*
X439320Y-178564D01*
X440848Y-177106D01*
X442377Y-176814D01*
X443905Y-177397D01*
X444997Y-178856D01*
G01X453982Y-190814D02*
X455291Y-192856D01*
X457038Y-194022D01*
X459003Y-194314D01*
X460750Y-194022D01*
X462497Y-192564D01*
X463588Y-190814D01*
X463807Y-189064D01*
X463370Y-187023D01*
X461842Y-185564D01*
X460313Y-184981D01*
X458348D01*
G01X460313D02*
X461623Y-184106D01*
X462715Y-182648D01*
X463152Y-180898D01*
X462715Y-179147D01*
X461623Y-177689D01*
X459658Y-176814D01*
X457693Y-177106D01*
X455728Y-178273D01*
G01X478905Y-194314D02*
Y-176814D01*
X470826Y-189356D01*
X481744D01*
G01X493348Y-194314D02*
X493785Y-190523D01*
X494440Y-187314D01*
X495313Y-184397D01*
X496405Y-181189D01*
X498152Y-176814D01*
X489418D01*
G01X410668Y-149314D02*
Y-131814D01*
X415908D01*
X417655Y-132689D01*
X418965Y-134731D01*
X419402Y-137064D01*
X418965Y-139397D01*
X417873Y-141147D01*
X415908Y-142023D01*
X410668D01*
G01X437338Y-133273D02*
X436028Y-132397D01*
X434500Y-131814D01*
X432753D01*
X430788Y-132689D01*
X429260Y-134147D01*
X428168Y-135898D01*
X427295Y-138814D01*
X427076Y-141439D01*
X427513Y-144064D01*
X428168Y-145814D01*
X429478Y-147564D01*
X431007Y-148731D01*
X432535Y-149314D01*
X434063D01*
X435592Y-148731D01*
X436902Y-147856D01*
X437994Y-146690D01*
G01X451781Y-139981D02*
X452655Y-139106D01*
X453310Y-137648D01*
X453747Y-135605D01*
X453310Y-133856D01*
X452437Y-132689D01*
X450908Y-131814D01*
X445013D01*
Y-149314D01*
X452218D01*
X453747Y-148148D01*
X454620Y-146397D01*
X455057Y-144356D01*
X454620Y-142314D01*
X453310Y-140564D01*
X451781Y-139981D01*
X445013D01*
G01X460985Y-155147D02*
X474085D01*
G01X480013Y-149314D02*
Y-131814D01*
X490057Y-149314D01*
Y-131814D01*
G01X502535Y-149314D02*
X500788Y-149022D01*
X499260Y-147856D01*
X497950Y-146106D01*
X497076Y-144064D01*
X496640Y-141731D01*
Y-139397D01*
X497076Y-137064D01*
X497950Y-135022D01*
X499260Y-133273D01*
X500788Y-132106D01*
X502535Y-131814D01*
X504281Y-132106D01*
X505810Y-133273D01*
X507120Y-135022D01*
X507994Y-137064D01*
X508430Y-139397D01*
Y-141731D01*
X507994Y-144064D01*
X507120Y-146106D01*
X505810Y-147856D01*
X504281Y-149022D01*
X502535Y-149314D01*
G01X553376Y-131814D02*
X558835Y-149314D01*
X564294Y-131814D01*
G01X580702Y-149314D02*
X571968D01*
Y-131814D01*
X580702D01*
G01X577208Y-140272D02*
X571968D01*
G01X589468Y-149314D02*
Y-131814D01*
X594927D01*
X596673Y-132689D01*
X597765Y-133856D01*
X598202Y-136189D01*
X597765Y-138523D01*
X596455Y-139981D01*
X594927Y-140856D01*
X589468D01*
G01X594927D02*
X598202Y-149314D01*
G01X611335Y-149897D02*
X610898Y-149606D01*
Y-149022D01*
X611335Y-148731D01*
X611772Y-149022D01*
Y-149606D01*
X611335Y-149897D01*
G01X571750Y-191981D02*
X573497Y-193439D01*
X575462Y-194314D01*
X577208D01*
X578955Y-193439D01*
X580265Y-191981D01*
X580920Y-189939D01*
X580483Y-187898D01*
X579392Y-186147D01*
X577427Y-184981D01*
X574807Y-184397D01*
X573278Y-183231D01*
X572623Y-181189D01*
X573060Y-179147D01*
X574152Y-177689D01*
X575680Y-176814D01*
X577208D01*
X578737Y-177397D01*
X580047Y-178856D01*
G01X598638Y-178273D02*
X597328Y-177397D01*
X595800Y-176814D01*
X594053D01*
X592088Y-177689D01*
X590560Y-179147D01*
X589468Y-180898D01*
X588595Y-183814D01*
X588376Y-186439D01*
X588813Y-189064D01*
X589468Y-190814D01*
X590778Y-192564D01*
X592307Y-193731D01*
X593835Y-194314D01*
X595363D01*
X596892Y-193731D01*
X598202Y-192856D01*
X599294Y-191690D01*
G01X691285Y-176814D02*
Y-194314D01*
G01X686263Y-176814D02*
X696307D01*
G01X703108Y-194314D02*
Y-176814D01*
X708785Y-191397D01*
X714462Y-176814D01*
Y-194314D01*
G01X720826D02*
X726285Y-176814D01*
X731744Y-194314D01*
G01X729778Y-188189D02*
X722791D01*
G01X739200Y-191981D02*
X740947Y-193439D01*
X742912Y-194314D01*
X744658D01*
X746405Y-193439D01*
X747715Y-191981D01*
X748370Y-189939D01*
X747933Y-187898D01*
X746842Y-186147D01*
X744877Y-184981D01*
X742257Y-184397D01*
X740728Y-183231D01*
X740073Y-181189D01*
X740510Y-179147D01*
X741602Y-177689D01*
X743130Y-176814D01*
X744658D01*
X746187Y-177397D01*
X747497Y-178856D01*
G01X756482Y-194314D02*
Y-176814D01*
G01X764778D02*
X756482Y-187606D01*
G01X766088Y-194314D02*
X760193Y-182648D01*
G01X686918Y-131814D02*
Y-149314D01*
X695652D01*
G01X712715D02*
Y-137648D01*
G01Y-139689D02*
X711842Y-138523D01*
X710531Y-137939D01*
X709003Y-137648D01*
X707475Y-138231D01*
X706165Y-139397D01*
X705291Y-141147D01*
X704855Y-143481D01*
X705291Y-145814D01*
X706165Y-147564D01*
X707475Y-148731D01*
X709003Y-149314D01*
X710531Y-149022D01*
X711842Y-148148D01*
X712715Y-146981D01*
G01X721700Y-154564D02*
X723010Y-155147D01*
X724757Y-154564D01*
X725848Y-153398D01*
X726722Y-151939D01*
X728031Y-147273D01*
X730870Y-137648D01*
G01X723883D02*
X728031Y-147273D01*
G01X740510Y-141439D02*
X747497D01*
X746842Y-139397D01*
X745750Y-138231D01*
X744222Y-137648D01*
X742693Y-137939D01*
X741383Y-138814D01*
X740510Y-140856D01*
X740073Y-142606D01*
Y-144356D01*
X740510Y-146106D01*
X741602Y-147856D01*
X742912Y-149022D01*
X744440Y-149314D01*
X745968Y-148731D01*
X747497Y-146981D01*
G01X758228Y-149314D02*
Y-137648D01*
G01Y-139981D02*
X759320Y-138814D01*
X760412Y-137939D01*
X761940Y-137648D01*
X763031Y-137939D01*
X764342Y-138814D01*
G01X851335Y-194314D02*
X849588Y-194022D01*
X848060Y-192856D01*
X846750Y-191106D01*
X845876Y-189064D01*
X845440Y-186731D01*
Y-184397D01*
X845876Y-182064D01*
X846750Y-180022D01*
X848060Y-178273D01*
X849588Y-177106D01*
X851335Y-176814D01*
X853081Y-177106D01*
X854610Y-178273D01*
X855920Y-180022D01*
X856794Y-182064D01*
X857230Y-184397D01*
Y-186731D01*
X856794Y-189064D01*
X855920Y-191106D01*
X854610Y-192856D01*
X853081Y-194022D01*
X851335Y-194314D01*
G01X853081Y-189647D02*
X855702Y-194314D01*
G01X864032Y-176814D02*
Y-189356D01*
X864905Y-191981D01*
X866652Y-193731D01*
X868835Y-194314D01*
X871018Y-193731D01*
X872765Y-191981D01*
X873638Y-189356D01*
Y-176814D01*
G01X883715D02*
X888955D01*
G01X886335D02*
Y-194314D01*
G01X883715D02*
X888955D01*
G01X898813D02*
Y-176814D01*
X908857Y-194314D01*
Y-176814D01*
G01X926138Y-178273D02*
X924828Y-177397D01*
X923300Y-176814D01*
X921553D01*
X919588Y-177689D01*
X918060Y-179147D01*
X916968Y-180898D01*
X916095Y-183814D01*
X915876Y-186439D01*
X916313Y-189064D01*
X916968Y-190814D01*
X918278Y-192564D01*
X919807Y-193731D01*
X921335Y-194314D01*
X922863D01*
X924392Y-193731D01*
X925702Y-192856D01*
X926794Y-191690D01*
G01X938835Y-194314D02*
Y-186439D01*
X934468Y-176814D01*
G01X943202D02*
X938835Y-186439D01*
G01X829032Y-149314D02*
Y-131814D01*
X833398D01*
X835145Y-132689D01*
X836455Y-133856D01*
X837547Y-135605D01*
X838420Y-137648D01*
X838638Y-140564D01*
X838420Y-143481D01*
X837547Y-145523D01*
X836455Y-147273D01*
X835145Y-148439D01*
X833398Y-149314D01*
X829032D01*
G01X848060Y-141439D02*
X855047D01*
X854392Y-139397D01*
X853300Y-138231D01*
X851772Y-137648D01*
X850243Y-137939D01*
X848933Y-138814D01*
X848060Y-140856D01*
X847623Y-142606D01*
Y-144356D01*
X848060Y-146106D01*
X849152Y-147856D01*
X850462Y-149022D01*
X851990Y-149314D01*
X853518Y-148731D01*
X855047Y-146981D01*
G01X865560Y-147273D02*
X866652Y-148439D01*
X868180Y-149314D01*
X869490D01*
X870800Y-148731D01*
X871673Y-147856D01*
X872110Y-146690D01*
X871892Y-144939D01*
X871018Y-144064D01*
X867088Y-142314D01*
X866215Y-140272D01*
X866652Y-138814D01*
X867525Y-137939D01*
X868835Y-137648D01*
X870145Y-137939D01*
X871455Y-138814D01*
G01X886335Y-137648D02*
Y-149314D01*
G01Y-132981D02*
X885898Y-132689D01*
Y-132106D01*
X886335Y-131814D01*
X886772Y-132106D01*
Y-132689D01*
X886335Y-132981D01*
G01X900778Y-153689D02*
X902307Y-154856D01*
X904053Y-155147D01*
X905581Y-154856D01*
X906892Y-153398D01*
X907765Y-151356D01*
Y-137648D01*
G01Y-139981D02*
X906892Y-138814D01*
X905581Y-137939D01*
X904053Y-137648D01*
X902307Y-138231D01*
X901215Y-139397D01*
X900341Y-141439D01*
X899905Y-143481D01*
X900123Y-145231D01*
X900997Y-147273D01*
X902307Y-148731D01*
X904053Y-149314D01*
X905363Y-149022D01*
X906892Y-147856D01*
X907765Y-146690D01*
G01X917623Y-149314D02*
Y-137648D01*
G01Y-140564D02*
X918497Y-139106D01*
X919807Y-137939D01*
X921553Y-137648D01*
X923081Y-137939D01*
X924392Y-139106D01*
X925047Y-141147D01*
Y-149314D01*
G01X935560Y-141439D02*
X942547D01*
X941892Y-139397D01*
X940800Y-138231D01*
X939272Y-137648D01*
X937743Y-137939D01*
X936433Y-138814D01*
X935560Y-140856D01*
X935123Y-142606D01*
Y-144356D01*
X935560Y-146106D01*
X936652Y-147856D01*
X937962Y-149022D01*
X939490Y-149314D01*
X941018Y-148731D01*
X942547Y-146981D01*
G01X953278Y-149314D02*
Y-137648D01*
G01Y-139981D02*
X954370Y-138814D01*
X955462Y-137939D01*
X956990Y-137648D01*
X958081Y-137939D01*
X959392Y-138814D01*
G01X1000035Y-176814D02*
X998288Y-177397D01*
X996978Y-178856D01*
X996105Y-180605D01*
X995450Y-182939D01*
X995232Y-185564D01*
X995450Y-188189D01*
X996105Y-190523D01*
X996978Y-192273D01*
X998288Y-193731D01*
X1000035Y-194314D01*
X1001781Y-193731D01*
X1003092Y-192273D01*
X1003965Y-190523D01*
X1004620Y-188189D01*
X1004838Y-185564D01*
X1004620Y-182939D01*
X1003965Y-180605D01*
X1003092Y-178856D01*
X1001781Y-177397D01*
X1000035Y-176814D01*
G01X1012732Y-190814D02*
X1014041Y-192856D01*
X1015788Y-194022D01*
X1017753Y-194314D01*
X1019500Y-194022D01*
X1021247Y-192564D01*
X1022338Y-190814D01*
X1022557Y-189064D01*
X1022120Y-187023D01*
X1020592Y-185564D01*
X1019063Y-184981D01*
X1017098D01*
G01X1019063D02*
X1020373Y-184106D01*
X1021465Y-182648D01*
X1021902Y-180898D01*
X1021465Y-179147D01*
X1020373Y-177689D01*
X1018408Y-176814D01*
X1016443Y-177106D01*
X1014478Y-178273D01*
G01X1031105Y-194897D02*
X1038965Y-176814D01*
G01X1052535Y-194314D02*
Y-176814D01*
X1049915Y-180314D01*
G01Y-194314D02*
X1055155D01*
G01X1065232Y-190814D02*
X1066541Y-192856D01*
X1068288Y-194022D01*
X1070253Y-194314D01*
X1072000Y-194022D01*
X1073747Y-192564D01*
X1074838Y-190814D01*
X1075057Y-189064D01*
X1074620Y-187023D01*
X1073092Y-185564D01*
X1071563Y-184981D01*
X1069598D01*
G01X1071563D02*
X1072873Y-184106D01*
X1073965Y-182648D01*
X1074402Y-180898D01*
X1073965Y-179147D01*
X1072873Y-177689D01*
X1070908Y-176814D01*
X1068943Y-177106D01*
X1066978Y-178273D01*
G01X1083605Y-194897D02*
X1091465Y-176814D01*
G01X1100887Y-179731D02*
X1102197Y-177981D01*
X1103725Y-177106D01*
X1105472Y-176814D01*
X1107655Y-177397D01*
X1109183Y-178856D01*
X1109620Y-180605D01*
X1109402Y-182356D01*
X1108528Y-183814D01*
X1104162Y-186731D01*
X1102197Y-188772D01*
X1100887Y-191690D01*
X1100450Y-194314D01*
X1109620D01*
G01X1122535Y-176814D02*
X1120788Y-177397D01*
X1119478Y-178856D01*
X1118605Y-180605D01*
X1117950Y-182939D01*
X1117732Y-185564D01*
X1117950Y-188189D01*
X1118605Y-190523D01*
X1119478Y-192273D01*
X1120788Y-193731D01*
X1122535Y-194314D01*
X1124281Y-193731D01*
X1125592Y-192273D01*
X1126465Y-190523D01*
X1127120Y-188189D01*
X1127338Y-185564D01*
X1127120Y-182939D01*
X1126465Y-180605D01*
X1125592Y-178856D01*
X1124281Y-177397D01*
X1122535Y-176814D01*
G01X1140035Y-194314D02*
Y-176814D01*
X1137415Y-180314D01*
G01Y-194314D02*
X1142655D01*
G01X1157098D02*
X1157535Y-190523D01*
X1158190Y-187314D01*
X1159063Y-184397D01*
X1160155Y-181189D01*
X1161902Y-176814D01*
X1153168D01*
G01X1047732Y-149314D02*
Y-131814D01*
X1052098D01*
X1053845Y-132689D01*
X1055155Y-133856D01*
X1056247Y-135605D01*
X1057120Y-137648D01*
X1057338Y-140564D01*
X1057120Y-143481D01*
X1056247Y-145523D01*
X1055155Y-147273D01*
X1053845Y-148439D01*
X1052098Y-149314D01*
X1047732D01*
G01X1073965D02*
Y-137648D01*
G01Y-139689D02*
X1073092Y-138523D01*
X1071781Y-137939D01*
X1070253Y-137648D01*
X1068725Y-138231D01*
X1067415Y-139397D01*
X1066541Y-141147D01*
X1066105Y-143481D01*
X1066541Y-145814D01*
X1067415Y-147564D01*
X1068725Y-148731D01*
X1070253Y-149314D01*
X1071781Y-149022D01*
X1073092Y-148148D01*
X1073965Y-146981D01*
G01X1087535Y-131814D02*
Y-149314D01*
G01X1084478Y-137648D02*
X1090592D01*
G01X1101760Y-141439D02*
X1108747D01*
X1108092Y-139397D01*
X1107000Y-138231D01*
X1105472Y-137648D01*
X1103943Y-137939D01*
X1102633Y-138814D01*
X1101760Y-140856D01*
X1101323Y-142606D01*
Y-144356D01*
X1101760Y-146106D01*
X1102852Y-147856D01*
X1104162Y-149022D01*
X1105690Y-149314D01*
X1107218Y-148731D01*
X1108747Y-146981D01*
M02*
